(kicad_pcb
	(version 20260206)
	(generator "pcbnew")
	(generator_version "10.0")
	(general
		(thickness 1.6)
		(legacy_teardrops no)
	)
	(paper "A4")
	(title_block
		(title "m-2 — Lightning_M.2_BRD.brd")
		(comment 1 "Lightning (Wiwynn / Facebook NVMe JBOF) / footprints 138-144 of 157")
	)
	(layers
		(0 "F.Cu" signal "TOP")
		(4 "In1.Cu" signal "L2GND")
		(6 "In2.Cu" signal "L3")
		(8 "In3.Cu" signal "L4GND")
		(10 "In4.Cu" signal "L5GND")
		(12 "In5.Cu" signal "L6")
		(14 "In6.Cu" signal "L7GND")
		(2 "B.Cu" signal "BOTTOM")
		(9 "F.Adhes" user "F.Adhesive")
		(11 "B.Adhes" user "B.Adhesive")
		(13 "F.Paste" user "Package Geometry/Pastemask Top")
		(15 "B.Paste" user "Package Geometry/Pastemask Bottom")
		(5 "F.SilkS" user "Ref Des/Silkscreen Top")
		(7 "B.SilkS" user "Ref Des/Silkscreen Bottom")
		(1 "F.Mask" user "Board Geometry/Soldermask Top")
		(3 "B.Mask" user "Board Geometry/Soldermask Bottom")
		(17 "Dwgs.User" user "User.Drawings")
		(19 "Cmts.User" user "User.Comments")
		(21 "Eco1.User" user "User.Eco1")
		(23 "Eco2.User" user "User.Eco2")
		(25 "Edge.Cuts" user "Board Geometry/Outline")
		(27 "Margin" user)
		(31 "F.CrtYd" user "Package Geometry/Place Bound Top")
		(29 "B.CrtYd" user "Package Geometry/Place Bound Bottom")
		(35 "F.Fab" user "Ref Des/Assembly Top")
		(33 "B.Fab" user "Ref Des/Assembly Bottom")
	)
	(footprint ""
		(layer "B.Cu")
		(at 43.766994 -76.2 180)
		(property "Reference" "PR31"
			(at 0 0 0)
			(layer "B.SilkS")
			(hide yes)
			(effects
				(font
					(size 1.27 1.27)
				)
				(justify mirror)
			)
		)
		(property "Value" "121KR2F-L-GP"
			(at -0.064008 -3.993896 180)
			(unlocked yes)
			(layer "B.Fab")
			(hide yes)
			(effects
				(font
					(size 1.016 1.016)
					(thickness 0.1524)
				)
				(justify mirror)
			)
		)
		(property "Device Type" "R402H16"
			(at -0.064008 -5.517896 180)
			(unlocked yes)
			(layer "B.Fab")
			(hide yes)
			(effects
				(font
					(size 1.016 1.016)
					(thickness 0.1524)
				)
				(justify mirror)
			)
		)
		(duplicate_pad_numbers_are_jumpers no)
		(fp_line
			(start 0.508 -0.9398)
			(end 0.508 0.9398)
			(stroke
				(width 0.1524)
				(type default)
			)
			(layer "B.SilkS")
		)
		(fp_line
			(start -0.508 -0.9398)
			(end 0.508 -0.9398)
			(stroke
				(width 0.1524)
				(type default)
			)
			(layer "B.SilkS")
		)
		(fp_rect
			(start 0.508 0.9398)
			(end -0.508 -0.9398)
			(stroke
				(width 0)
				(type default)
			)
			(fill no)
			(layer "B.CrtYd")
		)
		(fp_rect
			(start 0.508 0.9398)
			(end -0.508 -0.9398)
			(stroke
				(width 0)
				(type default)
			)
			(fill no)
			(layer "B.Fab")
		)
		(pad "1" smd custom
			(at 0 -0.4445)
			(size 0.1397 0.1397)
			(layers "B.Cu" "B.Mask" "B.Paste")
			(net "AGND_P3V3_DEV")
			(options
				(clearance outline)
				(anchor circle)
			)
			(primitives
				(gr_poly
					(pts
						(arc
							(start -0.1778 0.2794)
							(mid -0.249642 0.249642)
							(end -0.2794 0.1778)
						)
						(arc
							(start -0.2794 -0.1778)
							(mid -0.249642 -0.249642)
							(end -0.1778 -0.2794)
						)
						(arc
							(start 0.1778 -0.2794)
							(mid 0.249642 -0.249642)
							(end 0.2794 -0.1778)
						)
						(arc
							(start 0.2794 0.1778)
							(mid 0.249642 0.249642)
							(end 0.1778 0.2794)
						)
					)
					(width 0)
					(fill yes)
				)
			)
		)
		(pad "2" smd custom
			(at 0 0.4445)
			(size 0.1397 0.1397)
			(layers "B.Cu" "B.Mask" "B.Paste")
			(net "P3V3_DEV_TRIP")
			(options
				(clearance outline)
				(anchor circle)
			)
			(primitives
				(gr_poly
					(pts
						(arc
							(start -0.1778 0.2794)
							(mid -0.249642 0.249642)
							(end -0.2794 0.1778)
						)
						(arc
							(start -0.2794 -0.1778)
							(mid -0.249642 -0.249642)
							(end -0.1778 -0.2794)
						)
						(arc
							(start 0.1778 -0.2794)
							(mid 0.249642 -0.249642)
							(end 0.2794 -0.1778)
						)
						(arc
							(start 0.2794 0.1778)
							(mid 0.249642 0.249642)
							(end 0.1778 0.2794)
						)
					)
					(width 0)
					(fill yes)
				)
			)
		)
	)
	(footprint ""
		(layer "B.Cu")
		(at 67.183 -39.37)
		(property "Reference" "C41"
			(at 0 0 0)
			(layer "B.SilkS")
			(hide yes)
			(effects
				(font
					(size 1.27 1.27)
				)
				(justify mirror)
			)
		)
		(property "Value" "SCD1U16V2KX-3GP"
			(at -1.1811 -2.7051 0)
			(unlocked yes)
			(layer "B.Fab")
			(hide yes)
			(effects
				(font
					(size 1.016 1.016)
					(thickness 0.1524)
				)
				(justify mirror)
			)
		)
		(property "Device Type" "C402H22"
			(at -1.1811 -4.2291 0)
			(unlocked yes)
			(layer "B.Fab")
			(hide yes)
			(effects
				(font
					(size 1.016 1.016)
					(thickness 0.1524)
				)
				(justify mirror)
			)
		)
		(duplicate_pad_numbers_are_jumpers no)
		(fp_rect
			(start 0.4318 0.9525)
			(end -0.4318 -0.9525)
			(stroke
				(width 0)
				(type default)
			)
			(fill no)
			(layer "B.CrtYd")
		)
		(fp_rect
			(start 0.4318 0.9525)
			(end -0.4318 -0.9525)
			(stroke
				(width 0)
				(type default)
			)
			(fill no)
			(layer "B.Fab")
		)
		(pad "1" smd custom
			(at 0 -0.4445 180)
			(size 0.1524 0.1524)
			(layers "B.Cu" "B.Mask" "B.Paste")
			(net "P3V3_DPB")
			(options
				(clearance outline)
				(anchor circle)
			)
			(primitives
				(gr_poly
					(pts
						(arc
							(start 0.3048 0.2032)
							(mid 0.275042 0.275042)
							(end 0.2032 0.3048)
						)
						(arc
							(start -0.2032 0.3048)
							(mid -0.275042 0.275042)
							(end -0.3048 0.2032)
						)
						(arc
							(start -0.3048 -0.2032)
							(mid -0.275042 -0.275042)
							(end -0.2032 -0.3048)
						)
						(arc
							(start 0.2032 -0.3048)
							(mid 0.275042 -0.275042)
							(end 0.3048 -0.2032)
						)
					)
					(width 0)
					(fill yes)
				)
			)
		)
		(pad "2" smd custom
			(at 0 0.4445 180)
			(size 0.1524 0.1524)
			(layers "B.Cu" "B.Mask" "B.Paste")
			(net "GND")
			(options
				(clearance outline)
				(anchor circle)
			)
			(primitives
				(gr_poly
					(pts
						(arc
							(start 0.3048 0.2032)
							(mid 0.275042 0.275042)
							(end 0.2032 0.3048)
						)
						(arc
							(start -0.2032 0.3048)
							(mid -0.275042 0.275042)
							(end -0.3048 0.2032)
						)
						(arc
							(start -0.3048 -0.2032)
							(mid -0.275042 -0.275042)
							(end -0.2032 -0.3048)
						)
						(arc
							(start 0.2032 -0.3048)
							(mid 0.275042 -0.275042)
							(end 0.3048 -0.2032)
						)
					)
					(width 0)
					(fill yes)
				)
			)
		)
	)
	(footprint ""
		(layer "B.Cu")
		(at 49.608994 -80.518 -90)
		(property "Reference" "PR36"
			(at 0 0 90)
			(layer "B.SilkS")
			(hide yes)
			(effects
				(font
					(size 1.27 1.27)
				)
				(justify mirror)
			)
		)
		(property "Value" "0R2J-2-GP"
			(at -0.064008 -3.993896 270)
			(unlocked yes)
			(layer "B.Fab")
			(hide yes)
			(effects
				(font
					(size 1.016 1.016)
					(thickness 0.1524)
				)
				(justify mirror)
			)
		)
		(property "Device Type" "R402H16"
			(at -0.064008 -5.517896 270)
			(unlocked yes)
			(layer "B.Fab")
			(hide yes)
			(effects
				(font
					(size 1.016 1.016)
					(thickness 0.1524)
				)
				(justify mirror)
			)
		)
		(duplicate_pad_numbers_are_jumpers no)
		(fp_line
			(start -0.508 -0.9398)
			(end 0.508 -0.9398)
			(stroke
				(width 0.1524)
				(type default)
			)
			(layer "B.SilkS")
		)
		(fp_line
			(start 0.508 -0.9398)
			(end 0.508 0.9398)
			(stroke
				(width 0.1524)
				(type default)
			)
			(layer "B.SilkS")
		)
		(fp_rect
			(start 0.508 0.9398)
			(end -0.508 -0.9398)
			(stroke
				(width 0)
				(type default)
			)
			(fill no)
			(layer "B.CrtYd")
		)
		(fp_rect
			(start 0.508 0.9398)
			(end -0.508 -0.9398)
			(stroke
				(width 0)
				(type default)
			)
			(fill no)
			(layer "B.Fab")
		)
		(pad "1" smd custom
			(at 0 -0.4445 90)
			(size 0.1397 0.1397)
			(layers "B.Cu" "B.Mask" "B.Paste")
			(net "P3V3_DEV_ROVP")
			(options
				(clearance outline)
				(anchor circle)
			)
			(primitives
				(gr_poly
					(pts
						(arc
							(start -0.1778 0.2794)
							(mid -0.249642 0.249642)
							(end -0.2794 0.1778)
						)
						(arc
							(start -0.2794 -0.1778)
							(mid -0.249642 -0.249642)
							(end -0.1778 -0.2794)
						)
						(arc
							(start 0.1778 -0.2794)
							(mid 0.249642 -0.249642)
							(end 0.2794 -0.1778)
						)
						(arc
							(start 0.2794 0.1778)
							(mid 0.249642 0.249642)
							(end 0.1778 0.2794)
						)
					)
					(width 0)
					(fill yes)
				)
			)
		)
		(pad "2" smd custom
			(at 0 0.4445 90)
			(size 0.1397 0.1397)
			(layers "B.Cu" "B.Mask" "B.Paste")
			(net "AGND_P3V3_DEV")
			(options
				(clearance outline)
				(anchor circle)
			)
			(primitives
				(gr_poly
					(pts
						(arc
							(start -0.1778 0.2794)
							(mid -0.249642 0.249642)
							(end -0.2794 0.1778)
						)
						(arc
							(start -0.2794 -0.1778)
							(mid -0.249642 -0.249642)
							(end -0.1778 -0.2794)
						)
						(arc
							(start 0.1778 -0.2794)
							(mid 0.249642 -0.249642)
							(end 0.2794 -0.1778)
						)
						(arc
							(start 0.2794 0.1778)
							(mid 0.249642 0.249642)
							(end 0.1778 0.2794)
						)
					)
					(width 0)
					(fill yes)
				)
			)
		)
	)
	(footprint ""
		(layer "B.Cu")
		(at 60.579 -18.034 -90)
		(property "Reference" "C36"
			(at 0 0 90)
			(layer "B.SilkS")
			(hide yes)
			(effects
				(font
					(size 1.27 1.27)
				)
				(justify mirror)
			)
		)
		(property "Value" "SC10U6D3V5KX-4GP"
			(at 0.0762 -6.1214 270)
			(unlocked yes)
			(layer "B.Fab")
			(hide yes)
			(effects
				(font
					(size 1.016 1.016)
					(thickness 0.1524)
				)
				(justify mirror)
			)
		)
		(property "Device Type" "C805H58"
			(at 0.0762 -8.1534 270)
			(unlocked yes)
			(layer "B.Fab")
			(hide yes)
			(effects
				(font
					(size 1.016 1.016)
					(thickness 0.1524)
				)
				(justify mirror)
			)
		)
		(duplicate_pad_numbers_are_jumpers no)
		(fp_line
			(start -0.635 0)
			(end 0.635 0)
			(stroke
				(width 0.508)
				(type default)
			)
			(layer "B.SilkS")
		)
		(fp_rect
			(start 0.9652 1.778)
			(end -0.9652 -1.778)
			(stroke
				(width 0)
				(type default)
			)
			(fill no)
			(layer "B.CrtYd")
		)
		(fp_poly
			(pts
				(xy 0.9652 -1.778) (xy -0.9652 -1.778) (xy -0.9652 1.778) (xy 0.9652 1.778)
			)
			(stroke
				(width 0)
				(type default)
			)
			(fill no)
			(layer "B.Fab")
		)
		(pad "1" smd rect
			(at 0 -0.9652 90)
			(size 1.397 1.143)
			(layers "B.Cu" "B.Mask" "B.Paste")
			(net "P3V3_PWR")
		)
		(pad "2" smd rect
			(at 0 0.9652 90)
			(size 1.397 1.143)
			(layers "B.Cu" "B.Mask" "B.Paste")
			(net "GND")
		)
	)
	(footprint ""
		(layer "B.Cu")
		(at 30.861 -74.422 90)
		(property "Reference" "R54"
			(at 0 0 90)
			(layer "B.SilkS")
			(hide yes)
			(effects
				(font
					(size 1.27 1.27)
				)
				(justify mirror)
			)
		)
		(property "Value" "10KR2F-2-GP"
			(at -0.064008 -3.993896 90)
			(unlocked yes)
			(layer "B.Fab")
			(hide yes)
			(effects
				(font
					(size 1.016 1.016)
					(thickness 0.1524)
				)
				(justify mirror)
			)
		)
		(property "Device Type" "R402H16"
			(at -0.064008 -5.517896 90)
			(unlocked yes)
			(layer "B.Fab")
			(hide yes)
			(effects
				(font
					(size 1.016 1.016)
					(thickness 0.1524)
				)
				(justify mirror)
			)
		)
		(duplicate_pad_numbers_are_jumpers no)
		(fp_line
			(start 0.508 -0.9398)
			(end 0.508 0.9398)
			(stroke
				(width 0.1524)
				(type default)
			)
			(layer "B.SilkS")
		)
		(fp_line
			(start -0.508 -0.9398)
			(end 0.508 -0.9398)
			(stroke
				(width 0.1524)
				(type default)
			)
			(layer "B.SilkS")
		)
		(fp_rect
			(start 0.508 0.9398)
			(end -0.508 -0.9398)
			(stroke
				(width 0)
				(type default)
			)
			(fill no)
			(layer "B.CrtYd")
		)
		(fp_rect
			(start 0.508 0.9398)
			(end -0.508 -0.9398)
			(stroke
				(width 0)
				(type default)
			)
			(fill no)
			(layer "B.Fab")
		)
		(pad "1" smd custom
			(at 0 -0.4445 270)
			(size 0.1397 0.1397)
			(layers "B.Cu" "B.Mask" "B.Paste")
			(net "P3V3_PWR")
			(options
				(clearance outline)
				(anchor circle)
			)
			(primitives
				(gr_poly
					(pts
						(arc
							(start -0.1778 0.2794)
							(mid -0.249642 0.249642)
							(end -0.2794 0.1778)
						)
						(arc
							(start -0.2794 -0.1778)
							(mid -0.249642 -0.249642)
							(end -0.1778 -0.2794)
						)
						(arc
							(start 0.1778 -0.2794)
							(mid 0.249642 -0.249642)
							(end 0.2794 -0.1778)
						)
						(arc
							(start 0.2794 0.1778)
							(mid 0.249642 0.249642)
							(end 0.1778 0.2794)
						)
					)
					(width 0)
					(fill yes)
				)
			)
		)
		(pad "2" smd custom
			(at 0 0.4445 270)
			(size 0.1397 0.1397)
			(layers "B.Cu" "B.Mask" "B.Paste")
			(net "SSD_B1_SMB_OE")
			(options
				(clearance outline)
				(anchor circle)
			)
			(primitives
				(gr_poly
					(pts
						(arc
							(start -0.1778 0.2794)
							(mid -0.249642 0.249642)
							(end -0.2794 0.1778)
						)
						(arc
							(start -0.2794 -0.1778)
							(mid -0.249642 -0.249642)
							(end -0.1778 -0.2794)
						)
						(arc
							(start 0.1778 -0.2794)
							(mid 0.249642 -0.249642)
							(end 0.2794 -0.1778)
						)
						(arc
							(start 0.2794 0.1778)
							(mid 0.249642 0.249642)
							(end 0.1778 0.2794)
						)
					)
					(width 0)
					(fill yes)
				)
			)
		)
	)
	(footprint ""
		(layer "B.Cu")
		(at 65.151 -52.07 -90)
		(property "Reference" "R33"
			(at 0 0 90)
			(layer "B.SilkS")
			(hide yes)
			(effects
				(font
					(size 1.27 1.27)
				)
				(justify mirror)
			)
		)
		(property "Value" "47KR2F-GP"
			(at -0.064008 -3.993896 270)
			(unlocked yes)
			(layer "B.Fab")
			(hide yes)
			(effects
				(font
					(size 1.016 1.016)
					(thickness 0.1524)
				)
				(justify mirror)
			)
		)
		(property "Device Type" "R402H16"
			(at -0.064008 -5.517896 270)
			(unlocked yes)
			(layer "B.Fab")
			(hide yes)
			(effects
				(font
					(size 1.016 1.016)
					(thickness 0.1524)
				)
				(justify mirror)
			)
		)
		(duplicate_pad_numbers_are_jumpers no)
		(fp_line
			(start -0.508 -0.9398)
			(end 0.508 -0.9398)
			(stroke
				(width 0.1524)
				(type default)
			)
			(layer "B.SilkS")
		)
		(fp_line
			(start 0.508 -0.9398)
			(end 0.508 0.9398)
			(stroke
				(width 0.1524)
				(type default)
			)
			(layer "B.SilkS")
		)
		(fp_rect
			(start 0.508 0.9398)
			(end -0.508 -0.9398)
			(stroke
				(width 0)
				(type default)
			)
			(fill no)
			(layer "B.CrtYd")
		)
		(fp_rect
			(start 0.508 0.9398)
			(end -0.508 -0.9398)
			(stroke
				(width 0)
				(type default)
			)
			(fill no)
			(layer "B.Fab")
		)
		(pad "1" smd custom
			(at 0 -0.4445 90)
			(size 0.1397 0.1397)
			(layers "B.Cu" "B.Mask" "B.Paste")
			(net "Z50_SSD_A1_ALERT#")
			(options
				(clearance outline)
				(anchor circle)
			)
			(primitives
				(gr_poly
					(pts
						(arc
							(start -0.1778 0.2794)
							(mid -0.249642 0.249642)
							(end -0.2794 0.1778)
						)
						(arc
							(start -0.2794 -0.1778)
							(mid -0.249642 -0.249642)
							(end -0.1778 -0.2794)
						)
						(arc
							(start 0.1778 -0.2794)
							(mid 0.249642 -0.249642)
							(end 0.2794 -0.1778)
						)
						(arc
							(start 0.2794 0.1778)
							(mid 0.249642 0.249642)
							(end 0.1778 0.2794)
						)
					)
					(width 0)
					(fill yes)
				)
			)
		)
		(pad "2" smd custom
			(at 0 0.4445 90)
			(size 0.1397 0.1397)
			(layers "B.Cu" "B.Mask" "B.Paste")
			(net "P1V8_PWR")
			(options
				(clearance outline)
				(anchor circle)
			)
			(primitives
				(gr_poly
					(pts
						(arc
							(start -0.1778 0.2794)
							(mid -0.249642 0.249642)
							(end -0.2794 0.1778)
						)
						(arc
							(start -0.2794 -0.1778)
							(mid -0.249642 -0.249642)
							(end -0.1778 -0.2794)
						)
						(arc
							(start 0.1778 -0.2794)
							(mid 0.249642 -0.249642)
							(end 0.2794 -0.1778)
						)
						(arc
							(start 0.2794 0.1778)
							(mid 0.249642 0.249642)
							(end 0.1778 0.2794)
						)
					)
					(width 0)
					(fill yes)
				)
			)
		)
	)
	(footprint ""
		(layer "B.Cu")
		(at 58.244994 -42.164)
		(property "Reference" "R10"
			(at 0 0 0)
			(layer "B.SilkS")
			(hide yes)
			(effects
				(font
					(size 1.27 1.27)
				)
				(justify mirror)
			)
		)
		(property "Value" "4K7R2F-GP"
			(at -0.064008 -3.993896 0)
			(unlocked yes)
			(layer "B.Fab")
			(hide yes)
			(effects
				(font
					(size 1.016 1.016)
					(thickness 0.1524)
				)
				(justify mirror)
			)
		)
		(property "Device Type" "R402H16"
			(at -0.064008 -5.517896 0)
			(unlocked yes)
			(layer "B.Fab")
			(hide yes)
			(effects
				(font
					(size 1.016 1.016)
					(thickness 0.1524)
				)
				(justify mirror)
			)
		)
		(duplicate_pad_numbers_are_jumpers no)
		(fp_line
			(start -0.508 -0.9398)
			(end 0.508 -0.9398)
			(stroke
				(width 0.1524)
				(type default)
			)
			(layer "B.SilkS")
		)
		(fp_line
			(start 0.508 -0.9398)
			(end 0.508 0.9398)
			(stroke
				(width 0.1524)
				(type default)
			)
			(layer "B.SilkS")
		)
		(fp_rect
			(start 0.508 0.9398)
			(end -0.508 -0.9398)
			(stroke
				(width 0)
				(type default)
			)
			(fill no)
			(layer "B.CrtYd")
		)
		(fp_rect
			(start 0.508 0.9398)
			(end -0.508 -0.9398)
			(stroke
				(width 0)
				(type default)
			)
			(fill no)
			(layer "B.Fab")
		)
		(pad "1" smd custom
			(at 0 -0.4445 180)
			(size 0.1397 0.1397)
			(layers "B.Cu" "B.Mask" "B.Paste")
			(net "Z50_TEMP_1_A2")
			(options
				(clearance outline)
				(anchor circle)
			)
			(primitives
				(gr_poly
					(pts
						(arc
							(start -0.1778 0.2794)
							(mid -0.249642 0.249642)
							(end -0.2794 0.1778)
						)
						(arc
							(start -0.2794 -0.1778)
							(mid -0.249642 -0.249642)
							(end -0.1778 -0.2794)
						)
						(arc
							(start 0.1778 -0.2794)
							(mid 0.249642 -0.249642)
							(end 0.2794 -0.1778)
						)
						(arc
							(start 0.2794 0.1778)
							(mid 0.249642 0.249642)
							(end 0.1778 0.2794)
						)
					)
					(width 0)
					(fill yes)
				)
			)
		)
		(pad "2" smd custom
			(at 0 0.4445 180)
			(size 0.1397 0.1397)
			(layers "B.Cu" "B.Mask" "B.Paste")
			(net "GND")
			(options
				(clearance outline)
				(anchor circle)
			)
			(primitives
				(gr_poly
					(pts
						(arc
							(start -0.1778 0.2794)
							(mid -0.249642 0.249642)
							(end -0.2794 0.1778)
						)
						(arc
							(start -0.2794 -0.1778)
							(mid -0.249642 -0.249642)
							(end -0.1778 -0.2794)
						)
						(arc
							(start 0.1778 -0.2794)
							(mid 0.249642 -0.249642)
							(end 0.2794 -0.1778)
						)
						(arc
							(start 0.2794 0.1778)
							(mid 0.249642 0.249642)
							(end 0.1778 0.2794)
						)
					)
					(width 0)
					(fill yes)
				)
			)
		)
	)
)
